# SCM (Grand Teton) — schematic netlist excerpt (pin names and nets, part order shuffled) for the footprints in the layout excerpt that follows; sources: Cadence DE-HDL packaged netlist, KiCad conversion of 12092022_DA0F0TMDCD0_F0T_Management_Board_D_brd_V3_OCP.brd

R722  Q_RES  0 5% CHIP  pkg 0402LF  page 13 : A = FM_SLPS3_GF_R1_N ; B = FM_SLPS3_GF_N
C196  Q_CAP  1UF 25V 10% X6S  pkg C0402  page 50 : A = P3V3_RTC_AUX ; B = GND

(kicad_pcb
	(version 20260206)
	(generator "pcbnew")
	(generator_version "10.0")
	(general
		(thickness 1.6)
		(legacy_teardrops no)
	)
	(paper "A4")
	(title_block
		(title "12092022_DA0F0TMDCD0_F0T_Management_Board_D_brd_V3_OCP.brd")
		(comment 1 "Grand Teton / footprints 879-880 of 1440")
	)
	(layers
		(0 "F.Cu" signal "TOP")
		(4 "In1.Cu" signal "GND")
		(6 "In2.Cu" signal "IN1")
		(8 "In3.Cu" signal "GND1")
		(10 "In4.Cu" signal "IN2")
		(12 "In5.Cu" signal "VCC")
		(14 "In6.Cu" signal "VCC1")
		(16 "In7.Cu" signal "IN3")
		(18 "In8.Cu" signal "GND2")
		(20 "In9.Cu" signal "IN4")
		(22 "In10.Cu" signal "GND3")
		(2 "B.Cu" signal "BOTTOM")
		(9 "F.Adhes" user "F.Adhesive")
		(11 "B.Adhes" user "B.Adhesive")
		(13 "F.Paste" user "Package Geometry/Pastemask Top")
		(15 "B.Paste" user "Package Geometry/Pastemask Bottom")
		(5 "F.SilkS" user "Ref Des/Silkscreen Top")
		(7 "B.SilkS" user "Ref Des/Silkscreen Bottom")
		(1 "F.Mask" user "Board Geometry/Soldermask Top")
		(3 "B.Mask" user "Board Geometry/Soldermask Bottom")
		(17 "Dwgs.User" user "User.Drawings")
		(19 "Cmts.User" user "User.Comments")
		(21 "Eco1.User" user "User.Eco1")
		(23 "Eco2.User" user "User.Eco2")
		(25 "Edge.Cuts" user "Board Geometry/Outline")
		(27 "Margin" user)
		(31 "F.CrtYd" user "Package Geometry/Place Bound Top")
		(29 "B.CrtYd" user "Package Geometry/Place Bound Bottom")
		(35 "F.Fab" user "Ref Des/Assembly Top")
		(33 "B.Fab" user "Ref Des/Assembly Bottom")
	)
	(footprint ""
		(layer "B.Cu")
		(at 53.8734 -63.1952 -90)
		(property "Reference" "R722"
			(at 0 0 90)
			(layer "B.SilkS")
			(hide yes)
			(effects
				(font
					(size 1.27 1.27)
				)
				(justify mirror)
			)
		)
		(property "Value" ""
			(at 0 0 90)
			(layer "B.Fab")
			(effects
				(font
					(size 1.27 1.27)
				)
				(justify mirror)
			)
		)
		(duplicate_pad_numbers_are_jumpers no)
		(fp_line
			(start -0.7874 0.4064)
			(end 0.7874 0.4064)
			(stroke
				(width 0.1524)
				(type default)
			)
			(layer "B.SilkS")
		)
		(fp_line
			(start 0.7874 0.4064)
			(end 0.7874 -0.4064)
			(stroke
				(width 0.1524)
				(type default)
			)
			(layer "B.SilkS")
		)
		(fp_line
			(start -0.7874 -0.4064)
			(end -0.7874 0.4064)
			(stroke
				(width 0.1524)
				(type default)
			)
			(layer "B.SilkS")
		)
		(fp_line
			(start 0.7874 -0.4064)
			(end -0.7874 -0.4064)
			(stroke
				(width 0.1524)
				(type default)
			)
			(layer "B.SilkS")
		)
		(fp_line
			(start -0.67945 0.3048)
			(end -0.120396 0.3048)
			(stroke
				(width 0.1)
				(type default)
			)
			(layer "B.Fab")
		)
		(fp_line
			(start -0.120396 0.3048)
			(end -0.120396 0.2794)
			(stroke
				(width 0.1)
				(type default)
			)
			(layer "B.Fab")
		)
		(fp_line
			(start 0.12065 0.3048)
			(end 0.67945 0.3048)
			(stroke
				(width 0.1)
				(type default)
			)
			(layer "B.Fab")
		)
		(fp_line
			(start 0.67945 0.3048)
			(end 0.67945 -0.305054)
			(stroke
				(width 0.1)
				(type default)
			)
			(layer "B.Fab")
		)
		(fp_line
			(start -0.120396 0.2794)
			(end 0.12065 0.2794)
			(stroke
				(width 0.1)
				(type default)
			)
			(layer "B.Fab")
		)
		(fp_line
			(start 0.12065 0.2794)
			(end 0.12065 0.3048)
			(stroke
				(width 0.1)
				(type default)
			)
			(layer "B.Fab")
		)
		(fp_line
			(start -0.12065 -0.2794)
			(end -0.12065 -0.3048)
			(stroke
				(width 0.1)
				(type default)
			)
			(layer "B.Fab")
		)
		(fp_line
			(start 0.12065 -0.2794)
			(end -0.12065 -0.2794)
			(stroke
				(width 0.1)
				(type default)
			)
			(layer "B.Fab")
		)
		(fp_line
			(start -0.67945 -0.3048)
			(end -0.67945 0.3048)
			(stroke
				(width 0.1)
				(type default)
			)
			(layer "B.Fab")
		)
		(fp_line
			(start -0.12065 -0.3048)
			(end -0.67945 -0.3048)
			(stroke
				(width 0.1)
				(type default)
			)
			(layer "B.Fab")
		)
		(fp_line
			(start 0.12065 -0.305054)
			(end 0.12065 -0.2794)
			(stroke
				(width 0.1)
				(type default)
			)
			(layer "B.Fab")
		)
		(fp_line
			(start 0.67945 -0.305054)
			(end 0.12065 -0.305054)
			(stroke
				(width 0.1)
				(type default)
			)
			(layer "B.Fab")
		)
		(pad "1" smd circle
			(at 0.40005 0 90)
			(size 0 0)
			(layers "B.Cu" "B.Mask" "B.Paste")
			(net "FM_SLPS3_GF_R1_N")
		)
		(pad "2" smd circle
			(at -0.40005 0 90)
			(size 0 0)
			(layers "B.Cu" "B.Mask" "B.Paste")
			(net "FM_SLPS3_GF_N")
		)
	)
	(footprint ""
		(layer "B.Cu")
		(at 46.3804 -105.7783 90)
		(property "Reference" "C196"
			(at 0 0 90)
			(layer "B.SilkS")
			(hide yes)
			(effects
				(font
					(size 1.27 1.27)
				)
				(justify mirror)
			)
		)
		(property "Value" ""
			(at 0 0 90)
			(layer "B.Fab")
			(effects
				(font
					(size 1.27 1.27)
				)
				(justify mirror)
			)
		)
		(duplicate_pad_numbers_are_jumpers no)
		(fp_line
			(start 0.7874 -0.4064)
			(end -0.7874 -0.4064)
			(stroke
				(width 0.1524)
				(type default)
			)
			(layer "B.SilkS")
		)
		(fp_line
			(start -0.7874 -0.4064)
			(end -0.7874 0.4064)
			(stroke
				(width 0.1524)
				(type default)
			)
			(layer "B.SilkS")
		)
		(fp_line
			(start 0.7874 0.4064)
			(end 0.7874 -0.4064)
			(stroke
				(width 0.1524)
				(type default)
			)
			(layer "B.SilkS")
		)
		(fp_line
			(start -0.7874 0.4064)
			(end 0.7874 0.4064)
			(stroke
				(width 0.1524)
				(type default)
			)
			(layer "B.SilkS")
		)
		(fp_line
			(start 0.67945 -0.305054)
			(end 0.12065 -0.305054)
			(stroke
				(width 0.1)
				(type default)
			)
			(layer "B.Fab")
		)
		(fp_line
			(start 0.12065 -0.305054)
			(end 0.12065 -0.2794)
			(stroke
				(width 0.1)
				(type default)
			)
			(layer "B.Fab")
		)
		(fp_line
			(start -0.12065 -0.3048)
			(end -0.67945 -0.3048)
			(stroke
				(width 0.1)
				(type default)
			)
			(layer "B.Fab")
		)
		(fp_line
			(start -0.67945 -0.3048)
			(end -0.67945 0.3048)
			(stroke
				(width 0.1)
				(type default)
			)
			(layer "B.Fab")
		)
		(fp_line
			(start 0.12065 -0.2794)
			(end -0.12065 -0.2794)
			(stroke
				(width 0.1)
				(type default)
			)
			(layer "B.Fab")
		)
		(fp_line
			(start -0.12065 -0.2794)
			(end -0.12065 -0.3048)
			(stroke
				(width 0.1)
				(type default)
			)
			(layer "B.Fab")
		)
		(fp_line
			(start 0.12065 0.2794)
			(end 0.12065 0.3048)
			(stroke
				(width 0.1)
				(type default)
			)
			(layer "B.Fab")
		)
		(fp_line
			(start -0.120396 0.2794)
			(end 0.12065 0.2794)
			(stroke
				(width 0.1)
				(type default)
			)
			(layer "B.Fab")
		)
		(fp_line
			(start 0.67945 0.3048)
			(end 0.67945 -0.305054)
			(stroke
				(width 0.1)
				(type default)
			)
			(layer "B.Fab")
		)
		(fp_line
			(start 0.12065 0.3048)
			(end 0.67945 0.3048)
			(stroke
				(width 0.1)
				(type default)
			)
			(layer "B.Fab")
		)
		(fp_line
			(start -0.120396 0.3048)
			(end -0.120396 0.2794)
			(stroke
				(width 0.1)
				(type default)
			)
			(layer "B.Fab")
		)
		(fp_line
			(start -0.67945 0.3048)
			(end -0.120396 0.3048)
			(stroke
				(width 0.1)
				(type default)
			)
			(layer "B.Fab")
		)
		(pad "1" smd circle
			(at 0.40005 0 270)
			(size 0 0)
			(layers "B.Cu" "B.Mask" "B.Paste")
			(net "P3V3_RTC_AUX")
		)
		(pad "2" smd circle
			(at -0.40005 0 270)
			(size 0 0)
			(layers "B.Cu" "B.Mask" "B.Paste")
			(net "GND")
		)
	)
)
